# SCM (Grand Teton) — schematic netlist excerpt (pin names and nets, part order shuffled) for the footprints in the layout excerpt that follows; sources: Cadence DE-HDL packaged netlist, KiCad conversion of 12092022_DA0F0TMDCD0_F0T_Management_Board_D_brd_V3_OCP.brd

R597  Q_RES  750 1% CHIP  pkg 0402LF  page 47 : A = LED_POSTCODE_7 ; B = LED_POSTCODE_7_R
R396  Q_RES  100K 1% CHIP  pkg 0402LF  page 31 : A = P3V3_AUX ; B = UART_BIC_GF_RXD

(kicad_pcb
	(version 20260206)
	(generator "pcbnew")
	(generator_version "10.0")
	(general
		(thickness 1.6)
		(legacy_teardrops no)
	)
	(paper "A4")
	(title_block
		(title "12092022_DA0F0TMDCD0_F0T_Management_Board_D_brd_V3_OCP.brd")
		(comment 1 "Grand Teton / footprints 47-48 of 1440")
	)
	(layers
		(0 "F.Cu" signal "TOP")
		(4 "In1.Cu" signal "GND")
		(6 "In2.Cu" signal "IN1")
		(8 "In3.Cu" signal "GND1")
		(10 "In4.Cu" signal "IN2")
		(12 "In5.Cu" signal "VCC")
		(14 "In6.Cu" signal "VCC1")
		(16 "In7.Cu" signal "IN3")
		(18 "In8.Cu" signal "GND2")
		(20 "In9.Cu" signal "IN4")
		(22 "In10.Cu" signal "GND3")
		(2 "B.Cu" signal "BOTTOM")
		(9 "F.Adhes" user "F.Adhesive")
		(11 "B.Adhes" user "B.Adhesive")
		(13 "F.Paste" user "Package Geometry/Pastemask Top")
		(15 "B.Paste" user "Package Geometry/Pastemask Bottom")
		(5 "F.SilkS" user "Ref Des/Silkscreen Top")
		(7 "B.SilkS" user "Ref Des/Silkscreen Bottom")
		(1 "F.Mask" user "Board Geometry/Soldermask Top")
		(3 "B.Mask" user "Board Geometry/Soldermask Bottom")
		(17 "Dwgs.User" user "User.Drawings")
		(19 "Cmts.User" user "User.Comments")
		(21 "Eco1.User" user "User.Eco1")
		(23 "Eco2.User" user "User.Eco2")
		(25 "Edge.Cuts" user "Board Geometry/Outline")
		(27 "Margin" user)
		(31 "F.CrtYd" user "Package Geometry/Place Bound Top")
		(29 "B.CrtYd" user "Package Geometry/Place Bound Bottom")
		(35 "F.Fab" user "Ref Des/Assembly Top")
		(33 "B.Fab" user "Ref Des/Assembly Bottom")
	)
	(footprint ""
		(layer "F.Cu")
		(at 23.241 -64.897)
		(property "Reference" "R396"
			(at 0 0 0)
			(layer "F.SilkS")
			(hide yes)
			(effects
				(font
					(size 1.27 1.27)
				)
			)
		)
		(property "Value" ""
			(at 0 0 0)
			(layer "F.Fab")
			(effects
				(font
					(size 1.27 1.27)
				)
			)
		)
		(duplicate_pad_numbers_are_jumpers no)
		(fp_line
			(start -0.7874 -0.4064)
			(end 0.7874 -0.4064)
			(stroke
				(width 0.1524)
				(type default)
			)
			(layer "F.SilkS")
		)
		(fp_line
			(start -0.7874 0.4064)
			(end -0.7874 -0.4064)
			(stroke
				(width 0.1524)
				(type default)
			)
			(layer "F.SilkS")
		)
		(fp_line
			(start 0.7874 -0.4064)
			(end 0.7874 0.4064)
			(stroke
				(width 0.1524)
				(type default)
			)
			(layer "F.SilkS")
		)
		(fp_line
			(start 0.7874 0.4064)
			(end -0.7874 0.4064)
			(stroke
				(width 0.1524)
				(type default)
			)
			(layer "F.SilkS")
		)
		(fp_line
			(start -0.67945 -0.305054)
			(end -0.12065 -0.305054)
			(stroke
				(width 0.1)
				(type default)
			)
			(layer "F.Fab")
		)
		(fp_line
			(start -0.67945 0.3048)
			(end -0.67945 -0.305054)
			(stroke
				(width 0.1)
				(type default)
			)
			(layer "F.Fab")
		)
		(fp_line
			(start -0.12065 -0.305054)
			(end -0.12065 -0.2794)
			(stroke
				(width 0.1)
				(type default)
			)
			(layer "F.Fab")
		)
		(fp_line
			(start -0.12065 -0.2794)
			(end 0.12065 -0.2794)
			(stroke
				(width 0.1)
				(type default)
			)
			(layer "F.Fab")
		)
		(fp_line
			(start -0.12065 0.2794)
			(end -0.12065 0.3048)
			(stroke
				(width 0.1)
				(type default)
			)
			(layer "F.Fab")
		)
		(fp_line
			(start -0.12065 0.3048)
			(end -0.67945 0.3048)
			(stroke
				(width 0.1)
				(type default)
			)
			(layer "F.Fab")
		)
		(fp_line
			(start 0.120396 0.2794)
			(end -0.12065 0.2794)
			(stroke
				(width 0.1)
				(type default)
			)
			(layer "F.Fab")
		)
		(fp_line
			(start 0.120396 0.3048)
			(end 0.120396 0.2794)
			(stroke
				(width 0.1)
				(type default)
			)
			(layer "F.Fab")
		)
		(fp_line
			(start 0.12065 -0.3048)
			(end 0.67945 -0.3048)
			(stroke
				(width 0.1)
				(type default)
			)
			(layer "F.Fab")
		)
		(fp_line
			(start 0.12065 -0.2794)
			(end 0.12065 -0.3048)
			(stroke
				(width 0.1)
				(type default)
			)
			(layer "F.Fab")
		)
		(fp_line
			(start 0.67945 -0.3048)
			(end 0.67945 0.3048)
			(stroke
				(width 0.1)
				(type default)
			)
			(layer "F.Fab")
		)
		(fp_line
			(start 0.67945 0.3048)
			(end 0.120396 0.3048)
			(stroke
				(width 0.1)
				(type default)
			)
			(layer "F.Fab")
		)
		(pad "1" smd circle
			(at -0.40005 0)
			(size 0 0)
			(layers "F.Cu" "F.Mask" "F.Paste")
			(net "P3V3_AUX")
		)
		(pad "2" smd circle
			(at 0.40005 0)
			(size 0 0)
			(layers "F.Cu" "F.Mask" "F.Paste")
			(net "UART_BIC_GF_RXD")
		)
	)
	(footprint ""
		(layer "F.Cu")
		(at 72.46493 -30.957774 -90)
		(property "Reference" "R597"
			(at 0 0 270)
			(layer "F.SilkS")
			(hide yes)
			(effects
				(font
					(size 1.27 1.27)
				)
			)
		)
		(property "Value" ""
			(at 0 0 270)
			(layer "F.Fab")
			(effects
				(font
					(size 1.27 1.27)
				)
			)
		)
		(duplicate_pad_numbers_are_jumpers no)
		(fp_line
			(start -0.7874 0.4064)
			(end -0.7874 -0.4064)
			(stroke
				(width 0.1524)
				(type default)
			)
			(layer "F.SilkS")
		)
		(fp_line
			(start 0.7874 0.4064)
			(end -0.7874 0.4064)
			(stroke
				(width 0.1524)
				(type default)
			)
			(layer "F.SilkS")
		)
		(fp_line
			(start -0.7874 -0.4064)
			(end 0.7874 -0.4064)
			(stroke
				(width 0.1524)
				(type default)
			)
			(layer "F.SilkS")
		)
		(fp_line
			(start 0.7874 -0.4064)
			(end 0.7874 0.4064)
			(stroke
				(width 0.1524)
				(type default)
			)
			(layer "F.SilkS")
		)
		(fp_line
			(start -0.67945 0.3048)
			(end -0.67945 -0.305054)
			(stroke
				(width 0.1)
				(type default)
			)
			(layer "F.Fab")
		)
		(fp_line
			(start -0.12065 0.3048)
			(end -0.67945 0.3048)
			(stroke
				(width 0.1)
				(type default)
			)
			(layer "F.Fab")
		)
		(fp_line
			(start 0.120396 0.3048)
			(end 0.120396 0.2794)
			(stroke
				(width 0.1)
				(type default)
			)
			(layer "F.Fab")
		)
		(fp_line
			(start 0.67945 0.3048)
			(end 0.120396 0.3048)
			(stroke
				(width 0.1)
				(type default)
			)
			(layer "F.Fab")
		)
		(fp_line
			(start -0.12065 0.2794)
			(end -0.12065 0.3048)
			(stroke
				(width 0.1)
				(type default)
			)
			(layer "F.Fab")
		)
		(fp_line
			(start 0.120396 0.2794)
			(end -0.12065 0.2794)
			(stroke
				(width 0.1)
				(type default)
			)
			(layer "F.Fab")
		)
		(fp_line
			(start -0.12065 -0.2794)
			(end 0.12065 -0.2794)
			(stroke
				(width 0.1)
				(type default)
			)
			(layer "F.Fab")
		)
		(fp_line
			(start 0.12065 -0.2794)
			(end 0.12065 -0.3048)
			(stroke
				(width 0.1)
				(type default)
			)
			(layer "F.Fab")
		)
		(fp_line
			(start 0.12065 -0.3048)
			(end 0.67945 -0.3048)
			(stroke
				(width 0.1)
				(type default)
			)
			(layer "F.Fab")
		)
		(fp_line
			(start 0.67945 -0.3048)
			(end 0.67945 0.3048)
			(stroke
				(width 0.1)
				(type default)
			)
			(layer "F.Fab")
		)
		(fp_line
			(start -0.67945 -0.305054)
			(end -0.12065 -0.305054)
			(stroke
				(width 0.1)
				(type default)
			)
			(layer "F.Fab")
		)
		(fp_line
			(start -0.12065 -0.305054)
			(end -0.12065 -0.2794)
			(stroke
				(width 0.1)
				(type default)
			)
			(layer "F.Fab")
		)
		(pad "1" smd circle
			(at -0.40005 0 270)
			(size 0 0)
			(layers "F.Cu" "F.Mask" "F.Paste")
			(net "LED_POSTCODE_7")
		)
		(pad "2" smd circle
			(at 0.40005 0 270)
			(size 0 0)
			(layers "F.Cu" "F.Mask" "F.Paste")
			(net "LED_POSTCODE_7_R")
		)
	)
)
